(kicad_pcb
	(version 20241229)
	(generator "pcbnew")
	(generator_version "9.0")
	(general
		(thickness 1.6)
		(legacy_teardrops no)
	)
	(paper "A4")
	(title_block
		(title "LPDDR4 testbed")
		(date "2024-03-26")
		(rev "1.2.2")
		(comment 9 "footprint 16 of 66 (U1), pads 177-200 of 200")
	)
	(layers
		(0 "F.Cu" signal)
		(4 "In1.Cu" power)
		(6 "In2.Cu" power)
		(8 "In3.Cu" signal)
		(10 "In4.Cu" signal)
		(2 "B.Cu" signal)
		(9 "F.Adhes" user "F.Adhesive")
		(11 "B.Adhes" user "B.Adhesive")
		(13 "F.Paste" user)
		(15 "B.Paste" user)
		(5 "F.SilkS" user "F.Silkscreen")
		(7 "B.SilkS" user "B.Silkscreen")
		(1 "F.Mask" user)
		(3 "B.Mask" user)
		(17 "Dwgs.User" user "User.Drawings")
		(19 "Cmts.User" user "User.Comments")
		(21 "Eco1.User" user "User.Eco1")
		(23 "Eco2.User" user "User.Eco2")
		(25 "Edge.Cuts" user)
		(27 "Margin" user)
		(31 "F.CrtYd" user "F.Courtyard")
		(29 "B.CrtYd" user "B.Courtyard")
		(35 "F.Fab" user)
		(33 "B.Fab" user)
	)
	(footprint "antmicro-footprints:BGA-264-200_10x14.5mm_Layout12x22_P0.8x0.65mm"
		(locked yes)
		(layer "F.Cu")
		(at 149.375 86.125 180)
		(descr "http://www.issi.com/WW/pdf/43-46LQ32256A-AL.pdf")
		(property "Reference" "U1"
			(at 5.2 7.575 180)
			(layer "F.SilkS")
			(effects
				(font
					(size 0.7 0.7)
					(thickness 0.15)
				)
				(justify left bottom)
			)
		)
		(property "Value" "MT53E1G32D2NP-046"
			(at -5.5 9 180)
			(layer "F.Fab")
			(effects
				(font
					(size 0.7 0.7)
					(thickness 0.15)
				)
				(justify left bottom)
			)
		)
		(property "Description" "DRAM, Mobile LPDDR4, 32 Gbit, 1G x 32bit, 2.133 GHz, WFBGA, 200 Pins"
			(at 0 0 180)
			(layer "F.Fab")
			(hide yes)
			(effects
				(font
					(size 1.27 1.27)
					(thickness 0.15)
				)
			)
		)
		(property "Author" "Antmicro"
			(at 298.75 172.25 0)
			(layer "F.Fab")
			(hide yes)
			(effects
				(font
					(size 1 1)
					(thickness 0.15)
				)
			)
		)
		(property "License" "Apache-2.0"
			(at 298.75 172.25 0)
			(layer "F.Fab")
			(hide yes)
			(effects
				(font
					(size 1 1)
					(thickness 0.15)
				)
			)
		)
		(property "MPN" "MT53E1G32D2NP-046 WT:A"
			(at 298.75 172.25 0)
			(layer "F.Fab")
			(hide yes)
			(effects
				(font
					(size 1 1)
					(thickness 0.15)
				)
			)
		)
		(property "Manufacturer" "Micron Technology"
			(at 298.75 172.25 0)
			(layer "F.Fab")
			(hide yes)
			(effects
				(font
					(size 1 1)
					(thickness 0.15)
				)
			)
		)
		(sheetname "LPDDR4")
		(sheetfile "lpddr4.kicad_sch")
		(attr smd)
		(pad "V9" smd circle
			(at 2.004 4.217 180)
			(size 0.27 0.27)
			(layers "F.Cu" "F.Mask" "F.Paste")
			(net 243 "unconnected-(U1B-DQ13_B-PadV9)")
			(pinfunction "DQ13_B")
			(pintype "bidirectional+no_connect")
		)
		(pad "V10" smd circle
			(at 2.805 4.217 180)
			(size 0.27 0.27)
			(layers "F.Cu" "F.Mask" "F.Paste")
			(net 244 "unconnected-(U1B-DQS1_C_B-PadV10)")
			(pinfunction "DQS1_C_B")
			(pintype "bidirectional+no_connect")
		)
		(pad "V11" smd circle
			(at 3.604 4.217 180)
			(size 0.27 0.27)
			(layers "F.Cu" "F.Mask" "F.Paste")
			(net 245 "unconnected-(U1B-DQ10_B-PadV11)")
			(pinfunction "DQ10_B")
			(pintype "bidirectional+no_connect")
		)
		(pad "V12" smd circle
			(at 4.405 4.217 180)
			(size 0.27 0.27)
			(layers "F.Cu" "F.Mask" "F.Paste")
			(net 36 "GND")
			(pinfunction "VSS")
			(pintype "passive")
		)
		(pad "W1" smd circle
			(at -4.396 4.866 180)
			(size 0.27 0.27)
			(layers "F.Cu" "F.Mask" "F.Paste")
			(net 189 "VDDQ")
			(pinfunction "VDDQ")
			(pintype "passive")
		)
		(pad "W2" smd circle
			(at -3.596 4.866 180)
			(size 0.27 0.27)
			(layers "F.Cu" "F.Mask" "F.Paste")
			(net 36 "GND")
			(pinfunction "VSS")
			(pintype "passive")
		)
		(pad "W3" smd circle
			(at -2.795 4.866 180)
			(size 0.27 0.27)
			(layers "F.Cu" "F.Mask" "F.Paste")
			(net 248 "unconnected-(U1B-DQS0_T_B-PadW3)")
			(pinfunction "DQS0_T_B")
			(pintype "bidirectional+no_connect")
		)
		(pad "W4" smd circle
			(at -1.996 4.866 180)
			(size 0.27 0.27)
			(layers "F.Cu" "F.Mask" "F.Paste")
			(net 36 "GND")
			(pinfunction "VSS")
			(pintype "passive")
		)
		(pad "W5" smd circle
			(at -1.196 4.866 180)
			(size 0.27 0.27)
			(layers "F.Cu" "F.Mask" "F.Paste")
			(net 189 "VDDQ")
			(pinfunction "VDDQ")
			(pintype "passive")
		)
		(pad "W8" smd circle
			(at 1.205 4.866 180)
			(size 0.27 0.27)
			(layers "F.Cu" "F.Mask" "F.Paste")
			(net 189 "VDDQ")
			(pinfunction "VDDQ")
			(pintype "passive")
		)
		(pad "W9" smd circle
			(at 2.004 4.866 180)
			(size 0.27 0.27)
			(layers "F.Cu" "F.Mask" "F.Paste")
			(net 36 "GND")
			(pinfunction "VSS")
			(pintype "passive")
		)
		(pad "W10" smd circle
			(at 2.805 4.866 180)
			(size 0.27 0.27)
			(layers "F.Cu" "F.Mask" "F.Paste")
			(net 249 "unconnected-(U1B-DQS1_T_B-PadW10)")
			(pinfunction "DQS1_T_B")
			(pintype "bidirectional+no_connect")
		)
		(pad "W11" smd circle
			(at 3.604 4.866 180)
			(size 0.27 0.27)
			(layers "F.Cu" "F.Mask" "F.Paste")
			(net 36 "GND")
			(pinfunction "VSS")
			(pintype "passive")
		)
		(pad "W12" smd circle
			(at 4.405 4.866 180)
			(size 0.27 0.27)
			(layers "F.Cu" "F.Mask" "F.Paste")
			(net 189 "VDDQ")
			(pinfunction "VDDQ")
			(pintype "passive")
		)
		(pad "Y1" smd circle
			(at -4.396 5.517 180)
			(size 0.27 0.27)
			(layers "F.Cu" "F.Mask" "F.Paste")
			(net 36 "GND")
			(pinfunction "VSS")
			(pintype "passive")
		)
		(pad "Y2" smd circle
			(at -3.596 5.517 180)
			(size 0.27 0.27)
			(layers "F.Cu" "F.Mask" "F.Paste")
			(net 250 "unconnected-(U1B-DQ1_B-PadY2)")
			(pinfunction "DQ1_B")
			(pintype "bidirectional+no_connect")
		)
		(pad "Y3" smd circle
			(at -2.795 5.517 180)
			(size 0.27 0.27)
			(layers "F.Cu" "F.Mask" "F.Paste")
			(net 251 "unconnected-(U1B-DMI0_B-PadY3)")
			(pinfunction "DMI0_B")
			(pintype "bidirectional+no_connect")
		)
		(pad "Y4" smd circle
			(at -1.996 5.517 180)
			(size 0.27 0.27)
			(layers "F.Cu" "F.Mask" "F.Paste")
			(net 252 "unconnected-(U1B-DQ6_B-PadY4)")
			(pinfunction "DQ6_B")
			(pintype "bidirectional+no_connect")
		)
		(pad "Y5" smd circle
			(at -1.196 5.517 180)
			(size 0.27 0.27)
			(layers "F.Cu" "F.Mask" "F.Paste")
			(net 36 "GND")
			(pinfunction "VSS")
			(pintype "passive")
		)
		(pad "Y8" smd circle
			(at 1.205 5.517 180)
			(size 0.27 0.27)
			(layers "F.Cu" "F.Mask" "F.Paste")
			(net 36 "GND")
			(pinfunction "VSS")
			(pintype "passive")
		)
		(pad "Y9" smd circle
			(at 2.004 5.517 180)
			(size 0.27 0.27)
			(layers "F.Cu" "F.Mask" "F.Paste")
			(net 253 "unconnected-(U1B-DQ14_B-PadY9)")
			(pinfunction "DQ14_B")
			(pintype "bidirectional+no_connect")
		)
		(pad "Y10" smd circle
			(at 2.805 5.517 180)
			(size 0.27 0.27)
			(layers "F.Cu" "F.Mask" "F.Paste")
			(net 254 "unconnected-(U1B-DMI1_B-PadY10)")
			(pinfunction "DMI1_B")
			(pintype "bidirectional+no_connect")
		)
		(pad "Y11" smd circle
			(at 3.604 5.517 180)
			(size 0.27 0.27)
			(layers "F.Cu" "F.Mask" "F.Paste")
			(net 259 "unconnected-(U1B-DQ9_B-PadY11)")
			(pinfunction "DQ9_B")
			(pintype "bidirectional+no_connect")
		)
		(pad "Y12" smd circle
			(at 4.405 5.517 180)
			(size 0.27 0.27)
			(layers "F.Cu" "F.Mask" "F.Paste")
			(net 36 "GND")
			(pinfunction "VSS")
			(pintype "passive")
		)
	)
)
